(kicad_pcb
	(version 20260206)
	(generator "pcbnew")
	(generator_version "10.0")
	(general
		(thickness 1.6)
		(legacy_teardrops no)
	)
	(paper "A4")
	(title_block
		(title "peb — Lightning_PEB_BRD.brd")
		(comment 1 "Lightning (Wiwynn / Facebook NVMe JBOF) / footprints 380-386 of 2563")
	)
	(layers
		(0 "F.Cu" signal "TOP")
		(4 "In1.Cu" signal "L2GND")
		(6 "In2.Cu" signal "L3")
		(8 "In3.Cu" signal "L4VCC")
		(10 "In4.Cu" signal "L5VCC")
		(12 "In5.Cu" signal "L6")
		(14 "In6.Cu" signal "L7GND")
		(2 "B.Cu" signal "BOTTOM")
		(9 "F.Adhes" user "F.Adhesive")
		(11 "B.Adhes" user "B.Adhesive")
		(13 "F.Paste" user "Package Geometry/Pastemask Top")
		(15 "B.Paste" user "Package Geometry/Pastemask Bottom")
		(5 "F.SilkS" user "Ref Des/Silkscreen Top")
		(7 "B.SilkS" user "Ref Des/Silkscreen Bottom")
		(1 "F.Mask" user "Board Geometry/Soldermask Top")
		(3 "B.Mask" user "Board Geometry/Soldermask Bottom")
		(17 "Dwgs.User" user "User.Drawings")
		(19 "Cmts.User" user "User.Comments")
		(21 "Eco1.User" user "User.Eco1")
		(23 "Eco2.User" user "User.Eco2")
		(25 "Edge.Cuts" user "Board Geometry/Outline")
		(27 "Margin" user)
		(31 "F.CrtYd" user "Package Geometry/Place Bound Top")
		(29 "B.CrtYd" user "Package Geometry/Place Bound Bottom")
		(35 "F.Fab" user "Ref Des/Assembly Top")
		(33 "B.Fab" user "Ref Des/Assembly Bottom")
	)
	(footprint ""
		(layer "F.Cu")
		(at 25.3873 -175.6791)
		(property "Reference" "Q94"
			(at 0 0 0)
			(layer "F.SilkS")
			(hide yes)
			(effects
				(font
					(size 1.27 1.27)
				)
			)
		)
		(property "Value" "2N7002K-1-GP"
			(at 0.127 -8.9662 0)
			(unlocked yes)
			(layer "F.Fab")
			(hide yes)
			(effects
				(font
					(size 1.016 1.016)
					(thickness 0.1524)
				)
			)
		)
		(property "Device Type" "SOT23DGS2D4H44"
			(at 0.127 -10.4902 0)
			(unlocked yes)
			(layer "F.Fab")
			(hide yes)
			(effects
				(font
					(size 1.016 1.016)
					(thickness 0.1524)
				)
			)
		)
		(duplicate_pad_numbers_are_jumpers no)
		(fp_line
			(start -1.651 -1.778)
			(end -1.651 1.778)
			(stroke
				(width 0.1524)
				(type default)
			)
			(layer "F.SilkS")
		)
		(fp_line
			(start -1.651 1.778)
			(end 1.651 1.778)
			(stroke
				(width 0.1524)
				(type default)
			)
			(layer "F.SilkS")
		)
		(fp_line
			(start 1.651 -1.778)
			(end -1.651 -1.778)
			(stroke
				(width 0.1524)
				(type default)
			)
			(layer "F.SilkS")
		)
		(fp_line
			(start 1.651 1.778)
			(end 1.651 -1.778)
			(stroke
				(width 0.1524)
				(type default)
			)
			(layer "F.SilkS")
		)
		(fp_poly
			(pts
				(xy -1.778 1.8796) (xy -1.778 -1.8796) (xy 1.778 -1.8796) (xy 1.778 1.8796)
			)
			(stroke
				(width 0)
				(type default)
			)
			(fill no)
			(layer "F.CrtYd")
		)
		(fp_poly
			(pts
				(xy -1.778 1.8796) (xy -1.778 -1.8796) (xy 1.778 -1.8796) (xy 1.778 1.8796)
			)
			(stroke
				(width 0)
				(type default)
			)
			(fill no)
			(layer "F.Fab")
		)
		(pad "D" smd custom
			(at 0 -0.9525)
			(size 0.1905 0.1905)
			(layers "F.Cu" "F.Mask" "F.Paste")
			(net "MATED_P12V_EN")
			(options
				(clearance outline)
				(anchor circle)
			)
			(primitives
				(gr_poly
					(pts
						(arc
							(start -0.1778 0.5715)
							(mid -0.321484 0.511984)
							(end -0.381 0.3683)
						)
						(arc
							(start -0.381 -0.3683)
							(mid -0.321484 -0.511984)
							(end -0.1778 -0.5715)
						)
						(arc
							(start 0.1778 -0.5715)
							(mid 0.321484 -0.511984)
							(end 0.381 -0.3683)
						)
						(arc
							(start 0.381 0.3683)
							(mid 0.321484 0.511984)
							(end 0.1778 0.5715)
						)
					)
					(width 0)
					(fill yes)
				)
			)
		)
		(pad "G" smd custom
			(at -0.98425 0.9525)
			(size 0.1905 0.1905)
			(layers "F.Cu" "F.Mask" "F.Paste")
			(net "PCIE_MATED#_A")
			(options
				(clearance outline)
				(anchor circle)
			)
			(primitives
				(gr_poly
					(pts
						(arc
							(start -0.1778 0.5715)
							(mid -0.321484 0.511984)
							(end -0.381 0.3683)
						)
						(arc
							(start -0.381 -0.3683)
							(mid -0.321484 -0.511984)
							(end -0.1778 -0.5715)
						)
						(arc
							(start 0.1778 -0.5715)
							(mid 0.321484 -0.511984)
							(end 0.381 -0.3683)
						)
						(arc
							(start 0.381 0.3683)
							(mid 0.321484 0.511984)
							(end 0.1778 0.5715)
						)
					)
					(width 0)
					(fill yes)
				)
			)
		)
		(pad "S" smd custom
			(at 0.98425 0.9525)
			(size 0.1905 0.1905)
			(layers "F.Cu" "F.Mask" "F.Paste")
			(net "GND")
			(options
				(clearance outline)
				(anchor circle)
			)
			(primitives
				(gr_poly
					(pts
						(arc
							(start -0.1778 0.5715)
							(mid -0.321484 0.511984)
							(end -0.381 0.3683)
						)
						(arc
							(start -0.381 -0.3683)
							(mid -0.321484 -0.511984)
							(end -0.1778 -0.5715)
						)
						(arc
							(start 0.1778 -0.5715)
							(mid 0.321484 -0.511984)
							(end 0.381 -0.3683)
						)
						(arc
							(start 0.381 0.3683)
							(mid 0.321484 0.511984)
							(end 0.1778 0.5715)
						)
					)
					(width 0)
					(fill yes)
				)
			)
		)
	)
	(footprint ""
		(layer "F.Cu")
		(at 226.163124 -203.047092 180)
		(property "Reference" "R7962"
			(at 0 0 180)
			(layer "F.SilkS")
			(hide yes)
			(effects
				(font
					(size 1.27 1.27)
				)
			)
		)
		(property "Value" "0R2J-2-GP"
			(at 0.064008 -3.993896 180)
			(unlocked yes)
			(layer "F.Fab")
			(hide yes)
			(effects
				(font
					(size 1.016 1.016)
					(thickness 0.1524)
				)
			)
		)
		(property "Device Type" "R402H16"
			(at 0.064008 -5.517896 180)
			(unlocked yes)
			(layer "F.Fab")
			(hide yes)
			(effects
				(font
					(size 1.016 1.016)
					(thickness 0.1524)
				)
			)
		)
		(duplicate_pad_numbers_are_jumpers no)
		(fp_line
			(start 0.508 -0.9398)
			(end -0.508 -0.9398)
			(stroke
				(width 0.1524)
				(type default)
			)
			(layer "F.SilkS")
		)
		(fp_line
			(start -0.508 -0.9398)
			(end -0.508 0.9398)
			(stroke
				(width 0.1524)
				(type default)
			)
			(layer "F.SilkS")
		)
		(fp_rect
			(start -0.508 0.9398)
			(end 0.508 -0.9398)
			(stroke
				(width 0)
				(type default)
			)
			(fill no)
			(layer "F.CrtYd")
		)
		(fp_rect
			(start -0.508 0.9398)
			(end 0.508 -0.9398)
			(stroke
				(width 0)
				(type default)
			)
			(fill no)
			(layer "F.Fab")
		)
		(pad "1" smd custom
			(at 0 -0.4445 180)
			(size 0.1397 0.1397)
			(layers "F.Cu" "F.Mask" "F.Paste")
			(net "SSD_PWREN12")
			(options
				(clearance outline)
				(anchor circle)
			)
			(primitives
				(gr_poly
					(pts
						(arc
							(start -0.1778 -0.2794)
							(mid -0.249642 -0.249642)
							(end -0.2794 -0.1778)
						)
						(arc
							(start -0.2794 0.1778)
							(mid -0.249642 0.249642)
							(end -0.1778 0.2794)
						)
						(arc
							(start 0.1778 0.2794)
							(mid 0.249642 0.249642)
							(end 0.2794 0.1778)
						)
						(arc
							(start 0.2794 -0.1778)
							(mid 0.249642 -0.249642)
							(end 0.1778 -0.2794)
						)
					)
					(width 0)
					(fill yes)
				)
			)
		)
		(pad "2" smd custom
			(at 0 0.4445 180)
			(size 0.1397 0.1397)
			(layers "F.Cu" "F.Mask" "F.Paste")
			(net "SSD_PWREN12_R")
			(options
				(clearance outline)
				(anchor circle)
			)
			(primitives
				(gr_poly
					(pts
						(arc
							(start -0.1778 -0.2794)
							(mid -0.249642 -0.249642)
							(end -0.2794 -0.1778)
						)
						(arc
							(start -0.2794 0.1778)
							(mid -0.249642 0.249642)
							(end -0.1778 0.2794)
						)
						(arc
							(start 0.1778 0.2794)
							(mid 0.249642 0.249642)
							(end 0.2794 0.1778)
						)
						(arc
							(start 0.2794 -0.1778)
							(mid 0.249642 -0.249642)
							(end 0.1778 -0.2794)
						)
					)
					(width 0)
					(fill yes)
				)
			)
		)
	)
	(footprint ""
		(layer "F.Cu")
		(at 67.3862 -164.4396 -90)
		(property "Reference" "PC74"
			(at 0 0 270)
			(layer "F.SilkS")
			(hide yes)
			(effects
				(font
					(size 1.27 1.27)
				)
			)
		)
		(property "Value" "SCD01U25V2KX-3GP"
			(at 1.1811 -2.7051 270)
			(unlocked yes)
			(layer "F.Fab")
			(hide yes)
			(effects
				(font
					(size 1.016 1.016)
					(thickness 0.1524)
				)
			)
		)
		(property "Device Type" "C402H22"
			(at 1.1811 -4.2291 270)
			(unlocked yes)
			(layer "F.Fab")
			(hide yes)
			(effects
				(font
					(size 1.016 1.016)
					(thickness 0.1524)
				)
			)
		)
		(duplicate_pad_numbers_are_jumpers no)
		(fp_rect
			(start -0.4318 0.9525)
			(end 0.4318 -0.9525)
			(stroke
				(width 0)
				(type default)
			)
			(fill no)
			(layer "F.CrtYd")
		)
		(fp_rect
			(start -0.4318 0.9525)
			(end 0.4318 -0.9525)
			(stroke
				(width 0)
				(type default)
			)
			(fill no)
			(layer "F.Fab")
		)
		(pad "1" smd custom
			(at 0 -0.4445 270)
			(size 0.1524 0.1524)
			(layers "F.Cu" "F.Mask" "F.Paste")
			(net "VR_P1V538_STBY_EN_R")
			(options
				(clearance outline)
				(anchor circle)
			)
			(primitives
				(gr_poly
					(pts
						(arc
							(start 0.3048 -0.2032)
							(mid 0.275042 -0.275042)
							(end 0.2032 -0.3048)
						)
						(arc
							(start -0.2032 -0.3048)
							(mid -0.275042 -0.275042)
							(end -0.3048 -0.2032)
						)
						(arc
							(start -0.3048 0.2032)
							(mid -0.275042 0.275042)
							(end -0.2032 0.3048)
						)
						(arc
							(start 0.2032 0.3048)
							(mid 0.275042 0.275042)
							(end 0.3048 0.2032)
						)
					)
					(width 0)
					(fill yes)
				)
			)
		)
		(pad "2" smd custom
			(at 0 0.4445 270)
			(size 0.1524 0.1524)
			(layers "F.Cu" "F.Mask" "F.Paste")
			(net "GND")
			(options
				(clearance outline)
				(anchor circle)
			)
			(primitives
				(gr_poly
					(pts
						(arc
							(start 0.3048 -0.2032)
							(mid 0.275042 -0.275042)
							(end 0.2032 -0.3048)
						)
						(arc
							(start -0.2032 -0.3048)
							(mid -0.275042 -0.275042)
							(end -0.3048 -0.2032)
						)
						(arc
							(start -0.3048 0.2032)
							(mid -0.275042 0.275042)
							(end -0.2032 0.3048)
						)
						(arc
							(start 0.2032 0.3048)
							(mid 0.275042 0.275042)
							(end 0.3048 0.2032)
						)
					)
					(width 0)
					(fill yes)
				)
			)
		)
	)
	(footprint ""
		(layer "F.Cu")
		(at 42.4688 -192.8876 180)
		(property "Reference" "R866"
			(at 0 0 180)
			(layer "F.SilkS")
			(hide yes)
			(effects
				(font
					(size 1.27 1.27)
				)
			)
		)
		(property "Value" "0R2J-2-GP"
			(at 0.064008 -3.993896 180)
			(unlocked yes)
			(layer "F.Fab")
			(hide yes)
			(effects
				(font
					(size 1.016 1.016)
					(thickness 0.1524)
				)
			)
		)
		(property "Device Type" "R402H16"
			(at 0.064008 -5.517896 180)
			(unlocked yes)
			(layer "F.Fab")
			(hide yes)
			(effects
				(font
					(size 1.016 1.016)
					(thickness 0.1524)
				)
			)
		)
		(duplicate_pad_numbers_are_jumpers no)
		(fp_line
			(start 0.508 -0.9398)
			(end -0.508 -0.9398)
			(stroke
				(width 0.1524)
				(type default)
			)
			(layer "F.SilkS")
		)
		(fp_line
			(start -0.508 -0.9398)
			(end -0.508 0.9398)
			(stroke
				(width 0.1524)
				(type default)
			)
			(layer "F.SilkS")
		)
		(fp_rect
			(start -0.508 0.9398)
			(end 0.508 -0.9398)
			(stroke
				(width 0)
				(type default)
			)
			(fill no)
			(layer "F.CrtYd")
		)
		(fp_rect
			(start -0.508 0.9398)
			(end 0.508 -0.9398)
			(stroke
				(width 0)
				(type default)
			)
			(fill no)
			(layer "F.Fab")
		)
		(pad "1" smd custom
			(at 0 -0.4445 180)
			(size 0.1397 0.1397)
			(layers "F.Cu" "F.Mask" "F.Paste")
			(net "BUF_I2C9_CLKBUF2_SDA_R")
			(options
				(clearance outline)
				(anchor circle)
			)
			(primitives
				(gr_poly
					(pts
						(arc
							(start -0.1778 -0.2794)
							(mid -0.249642 -0.249642)
							(end -0.2794 -0.1778)
						)
						(arc
							(start -0.2794 0.1778)
							(mid -0.249642 0.249642)
							(end -0.1778 0.2794)
						)
						(arc
							(start 0.1778 0.2794)
							(mid 0.249642 0.249642)
							(end 0.2794 0.1778)
						)
						(arc
							(start 0.2794 -0.1778)
							(mid 0.249642 -0.249642)
							(end 0.1778 -0.2794)
						)
					)
					(width 0)
					(fill yes)
				)
			)
		)
		(pad "2" smd custom
			(at 0 0.4445 180)
			(size 0.1397 0.1397)
			(layers "F.Cu" "F.Mask" "F.Paste")
			(net "BUF_I2C9_CLKBUF2_SDA")
			(options
				(clearance outline)
				(anchor circle)
			)
			(primitives
				(gr_poly
					(pts
						(arc
							(start -0.1778 -0.2794)
							(mid -0.249642 -0.249642)
							(end -0.2794 -0.1778)
						)
						(arc
							(start -0.2794 0.1778)
							(mid -0.249642 0.249642)
							(end -0.1778 0.2794)
						)
						(arc
							(start 0.1778 0.2794)
							(mid 0.249642 0.249642)
							(end 0.2794 0.1778)
						)
						(arc
							(start 0.2794 -0.1778)
							(mid 0.249642 -0.249642)
							(end 0.1778 -0.2794)
						)
					)
					(width 0)
					(fill yes)
				)
			)
		)
	)
	(footprint ""
		(layer "F.Cu")
		(at 50.673 -177.165)
		(property "Reference" "R899"
			(at 0 0 0)
			(layer "F.SilkS")
			(hide yes)
			(effects
				(font
					(size 1.27 1.27)
				)
			)
		)
		(property "Value" "0R2J-2-GP"
			(at 0.064008 -3.993896 0)
			(unlocked yes)
			(layer "F.Fab")
			(hide yes)
			(effects
				(font
					(size 1.016 1.016)
					(thickness 0.1524)
				)
			)
		)
		(property "Device Type" "R402H16"
			(at 0.064008 -5.517896 0)
			(unlocked yes)
			(layer "F.Fab")
			(hide yes)
			(effects
				(font
					(size 1.016 1.016)
					(thickness 0.1524)
				)
			)
		)
		(duplicate_pad_numbers_are_jumpers no)
		(fp_line
			(start -0.508 -0.9398)
			(end -0.508 0.9398)
			(stroke
				(width 0.1524)
				(type default)
			)
			(layer "F.SilkS")
		)
		(fp_line
			(start 0.508 -0.9398)
			(end -0.508 -0.9398)
			(stroke
				(width 0.1524)
				(type default)
			)
			(layer "F.SilkS")
		)
		(fp_rect
			(start -0.508 0.9398)
			(end 0.508 -0.9398)
			(stroke
				(width 0)
				(type default)
			)
			(fill no)
			(layer "F.CrtYd")
		)
		(fp_rect
			(start -0.508 0.9398)
			(end 0.508 -0.9398)
			(stroke
				(width 0)
				(type default)
			)
			(fill no)
			(layer "F.Fab")
		)
		(pad "1" smd custom
			(at 0 -0.4445)
			(size 0.1397 0.1397)
			(layers "F.Cu" "F.Mask" "F.Paste")
			(net "BMC_I2C8_CLKBUF1_SDA_R")
			(options
				(clearance outline)
				(anchor circle)
			)
			(primitives
				(gr_poly
					(pts
						(arc
							(start -0.1778 -0.2794)
							(mid -0.249642 -0.249642)
							(end -0.2794 -0.1778)
						)
						(arc
							(start -0.2794 0.1778)
							(mid -0.249642 0.249642)
							(end -0.1778 0.2794)
						)
						(arc
							(start 0.1778 0.2794)
							(mid 0.249642 0.249642)
							(end 0.2794 0.1778)
						)
						(arc
							(start 0.2794 -0.1778)
							(mid 0.249642 -0.249642)
							(end 0.1778 -0.2794)
						)
					)
					(width 0)
					(fill yes)
				)
			)
		)
		(pad "2" smd custom
			(at 0 0.4445)
			(size 0.1397 0.1397)
			(layers "F.Cu" "F.Mask" "F.Paste")
			(net "BMC_I2C8_CLKBUF1_SDA")
			(options
				(clearance outline)
				(anchor circle)
			)
			(primitives
				(gr_poly
					(pts
						(arc
							(start -0.1778 -0.2794)
							(mid -0.249642 -0.249642)
							(end -0.2794 -0.1778)
						)
						(arc
							(start -0.2794 0.1778)
							(mid -0.249642 0.249642)
							(end -0.1778 0.2794)
						)
						(arc
							(start 0.1778 0.2794)
							(mid 0.249642 0.249642)
							(end 0.2794 0.1778)
						)
						(arc
							(start 0.2794 -0.1778)
							(mid 0.249642 -0.249642)
							(end 0.1778 -0.2794)
						)
					)
					(width 0)
					(fill yes)
				)
			)
		)
	)
	(footprint ""
		(layer "F.Cu")
		(at 16.383 -107.315)
		(property "Reference" "PR91"
			(at 0 0 0)
			(layer "F.SilkS")
			(hide yes)
			(effects
				(font
					(size 1.27 1.27)
				)
			)
		)
		(property "Value" "2K74R2F-GP"
			(at 0.064008 -3.993896 0)
			(unlocked yes)
			(layer "F.Fab")
			(hide yes)
			(effects
				(font
					(size 1.016 1.016)
					(thickness 0.1524)
				)
			)
		)
		(property "Device Type" "R402H16"
			(at 0.064008 -5.517896 0)
			(unlocked yes)
			(layer "F.Fab")
			(hide yes)
			(effects
				(font
					(size 1.016 1.016)
					(thickness 0.1524)
				)
			)
		)
		(duplicate_pad_numbers_are_jumpers no)
		(fp_line
			(start -0.508 -0.9398)
			(end -0.508 0.9398)
			(stroke
				(width 0.1524)
				(type default)
			)
			(layer "F.SilkS")
		)
		(fp_line
			(start 0.508 -0.9398)
			(end -0.508 -0.9398)
			(stroke
				(width 0.1524)
				(type default)
			)
			(layer "F.SilkS")
		)
		(fp_rect
			(start -0.508 0.9398)
			(end 0.508 -0.9398)
			(stroke
				(width 0)
				(type default)
			)
			(fill no)
			(layer "F.CrtYd")
		)
		(fp_rect
			(start -0.508 0.9398)
			(end 0.508 -0.9398)
			(stroke
				(width 0)
				(type default)
			)
			(fill no)
			(layer "F.Fab")
		)
		(pad "1" smd custom
			(at 0 -0.4445)
			(size 0.1397 0.1397)
			(layers "F.Cu" "F.Mask" "F.Paste")
			(net "P1V26_PWR")
			(options
				(clearance outline)
				(anchor circle)
			)
			(primitives
				(gr_poly
					(pts
						(arc
							(start -0.1778 -0.2794)
							(mid -0.249642 -0.249642)
							(end -0.2794 -0.1778)
						)
						(arc
							(start -0.2794 0.1778)
							(mid -0.249642 0.249642)
							(end -0.1778 0.2794)
						)
						(arc
							(start 0.1778 0.2794)
							(mid 0.249642 0.249642)
							(end 0.2794 0.1778)
						)
						(arc
							(start 0.2794 -0.1778)
							(mid 0.249642 -0.249642)
							(end 0.1778 -0.2794)
						)
					)
					(width 0)
					(fill yes)
				)
			)
		)
		(pad "2" smd custom
			(at 0 0.4445)
			(size 0.1397 0.1397)
			(layers "F.Cu" "F.Mask" "F.Paste")
			(net "VR_P1V26_STBY_FB")
			(options
				(clearance outline)
				(anchor circle)
			)
			(primitives
				(gr_poly
					(pts
						(arc
							(start -0.1778 -0.2794)
							(mid -0.249642 -0.249642)
							(end -0.2794 -0.1778)
						)
						(arc
							(start -0.2794 0.1778)
							(mid -0.249642 0.249642)
							(end -0.1778 0.2794)
						)
						(arc
							(start 0.1778 0.2794)
							(mid 0.249642 0.249642)
							(end 0.2794 0.1778)
						)
						(arc
							(start 0.2794 -0.1778)
							(mid 0.249642 -0.249642)
							(end 0.1778 -0.2794)
						)
					)
					(width 0)
					(fill yes)
				)
			)
		)
	)
	(footprint ""
		(layer "F.Cu")
		(at 117.568472 -30.638496 180)
		(property "Reference" "R2960"
			(at 0 0 180)
			(layer "F.SilkS")
			(hide yes)
			(effects
				(font
					(size 1.27 1.27)
				)
			)
		)
		(property "Value" "0R2J-2-GP"
			(at 0.064008 -3.993896 180)
			(unlocked yes)
			(layer "F.Fab")
			(hide yes)
			(effects
				(font
					(size 1.016 1.016)
					(thickness 0.1524)
				)
			)
		)
		(property "Device Type" "R402H16"
			(at 0.064008 -5.517896 180)
			(unlocked yes)
			(layer "F.Fab")
			(hide yes)
			(effects
				(font
					(size 1.016 1.016)
					(thickness 0.1524)
				)
			)
		)
		(duplicate_pad_numbers_are_jumpers no)
		(fp_line
			(start 0.508 -0.9398)
			(end -0.508 -0.9398)
			(stroke
				(width 0.1524)
				(type default)
			)
			(layer "F.SilkS")
		)
		(fp_line
			(start -0.508 -0.9398)
			(end -0.508 0.9398)
			(stroke
				(width 0.1524)
				(type default)
			)
			(layer "F.SilkS")
		)
		(fp_rect
			(start -0.508 0.9398)
			(end 0.508 -0.9398)
			(stroke
				(width 0)
				(type default)
			)
			(fill no)
			(layer "F.CrtYd")
		)
		(fp_rect
			(start -0.508 0.9398)
			(end 0.508 -0.9398)
			(stroke
				(width 0)
				(type default)
			)
			(fill no)
			(layer "F.Fab")
		)
		(pad "1" smd custom
			(at 0 -0.4445 180)
			(size 0.1397 0.1397)
			(layers "F.Cu" "F.Mask" "F.Paste")
			(net "U54_SDA")
			(options
				(clearance outline)
				(anchor circle)
			)
			(primitives
				(gr_poly
					(pts
						(arc
							(start -0.1778 -0.2794)
							(mid -0.249642 -0.249642)
							(end -0.2794 -0.1778)
						)
						(arc
							(start -0.2794 0.1778)
							(mid -0.249642 0.249642)
							(end -0.1778 0.2794)
						)
						(arc
							(start 0.1778 0.2794)
							(mid 0.249642 0.249642)
							(end 0.2794 0.1778)
						)
						(arc
							(start 0.2794 -0.1778)
							(mid 0.249642 -0.249642)
							(end 0.1778 -0.2794)
						)
					)
					(width 0)
					(fill yes)
				)
			)
		)
		(pad "2" smd custom
			(at 0 0.4445 180)
			(size 0.1397 0.1397)
			(layers "F.Cu" "F.Mask" "F.Paste")
			(net "BMC_I2C1_MINI1_SDA_S")
			(options
				(clearance outline)
				(anchor circle)
			)
			(primitives
				(gr_poly
					(pts
						(arc
							(start -0.1778 -0.2794)
							(mid -0.249642 -0.249642)
							(end -0.2794 -0.1778)
						)
						(arc
							(start -0.2794 0.1778)
							(mid -0.249642 0.249642)
							(end -0.1778 0.2794)
						)
						(arc
							(start 0.1778 0.2794)
							(mid 0.249642 0.249642)
							(end 0.2794 0.1778)
						)
						(arc
							(start 0.2794 -0.1778)
							(mid 0.249642 -0.249642)
							(end 0.1778 -0.2794)
						)
					)
					(width 0)
					(fill yes)
				)
			)
		)
	)
)
